FILE_TYPE = CONNECTIVITY;
{Allegro Design Entry HDL 17.2-2016 S081 (4005846) 1/11/2022}
"PAGE_NUMBER" = 301;
0"NC";
1"AGND_HSC\g";
2"AGND_HSC\g";
3"AGND_HSC\g";
4"AGND_HSC\g";
5"HSC_VDD\g";
6"P12V_PSU\g";
7"AGND_HSC\g";
8"HSC_VDD\g";
9"AGND_HSC\g";
10"P12V_PSU\g";
11"AGND_HSC\g";
12"P12V_AUX\g";
13"AGND_HSC\g";
14"P12V_AUX\g";
15"HSC_ON";
16"HSC_MODE_1";
17"HSC_VDD_R_1";
18"HSC_SCREF";
19"HSC_D_OC_1";
20"HSC_FLT_TYPE_1";
21"HSC_FAULT";
22"HSC_VTEMP";
23"HSC_SS";
24"HSC_MODE_2";
25"HSC_SCREF_2";
26"HSC_IMON";
27"HSC_CS_2";
28"HSC_OCREF";
29"HSC_ON";
30"HSC_VDD_R_2";
31"HSC_OCREF";
32"HSC_CS_1";
33"HSC_SCREF_1";
34"HSC_IMON";
35"HSC_SCREF";
36"HSC_NC1_2";
37"HSC_D_OC_R";
38"HSC_FLT_TYPE";
39"HSC_FLT_TYPE";
40"HSC_D_OC_R";
41"HSC_SS";
42"HSC_VTEMP";
43"HSC_FAULT";
44"HSC_FLT_TYPE_2";
45"HSC_D_OC_2";
46"HSC_NC1_1";
%"UNIVERSAL_GND"
"1","(-2875,-2350)","0","logical_power","I1";
;
HDL_POWER"AGND_HSC"
CDS_LIB"logical_power";
"A"3;
%"Q_CAP"
"1","(-2200,-2025)","0","pure_quanta","I11";
;
PART_NUMBER"CH21006KB16"
VALUE"1NF"
VOLTAGE"50V"
MATERIAL"EMPTY"
PACK_TYPE"0402"
LOCATION"PC2348"
TOLERANCE"10%"
CDS_LIB"pure_quanta"
$SEC"1"
CDS_SEC"1";
"B"
$PN"2"3;
"A"
$PN"1"28;
%"Q_RES"
"2","(-1725,-2025)","0","pure_quanta","I12";
;
PART_NUMBER"CS22002BB07"
VALUE"2K"
TOLERANCE"0.1%"
ROOM"HSC1_BOM1"
WATTAGE"1/16W"
PACK_TYPE"0402LF"
MATERIAL"CHIP"
LOCATION"PR3915"
CDS_LIB"pure_quanta"
$SEC"1"
CDS_SEC"1";
"A"
$PN"1"27;
"B"
$PN"2"3;
%"Q_RES"
"2","(-1200,-2025)","0","pure_quanta","I13";
;
PART_NUMBER"CS22002BB07"
VALUE"2K"
PACK_TYPE"0402LF"
MATERIAL"CHIP"
ROOM"HSC1_BOM1"
WATTAGE"1/16W"
TOLERANCE"0.1%"
$LOCATION"PR1101"
CDS_LIB"pure_quanta"
CDS_LOCATION"PR1101"
$SEC"1"
CDS_SEC"1";
"A"
$PN"1"26;
"B"
$PN"2"3;
%"MP5991GLUZ"
"1","(-225,-1275)","0","pure_quanta","I14";
;
PART_NUMBER"AL005991A00"
VALUE"MP5991GLU-Z"
PART_TYPE"SMLF"
MATERIAL"IC"
ROOM"HSC1_BOM1"
LOCATION"PU288"
NEEDS_NO_SIZE"TRUE"
CDS_LMAN_SYM_OUTLINE"-325,775,325,-775"
CDS_LIB"pure_quanta"
SEC_TYPE""
SEC"1";
"NC1"
$PN"7"36;
"FLT_TYPE"
$PN"6"44;
"SCREF_OCWREF"
$PN"17"25;
"MODE"
$PN"8"24;
"VOUT10"
$PN"32"12;
"VOUT9"
$PN"31"12;
"VOUT8"
$PN"30"12;
"VOUT7"
$PN"29"12;
"VOUT6"
$PN"28"12;
"VOUT5"
$PN"27"12;
"VIN9"
$PN"33"6;
"VIN8"
$PN"16"6;
"VIN7"
$PN"15"6;
"VIN6"
$PN"14"6;
"D_OC"
$PN"3"45;
"VOUT4"
$PN"26"12;
"VOUT3"
$PN"25"12;
"VOUT2"
$PN"2"12;
"VOUT1"
$PN"1"12;
"VTEMP"
$PN"18"42;
"GOK"
$PN"5"43;
"SS"
$PN"19"41;
"GND"
$PN"20"3;
"VDD33"
$PN"21"30;
"IMON"
$PN"22"26;
"CS"
$PN"23"27;
"OCREF"
$PN"24"28;
"ON"
$PN"4"29;
"VIN5"
$PN"13"6;
"VIN4"
$PN"12"6;
"VIN3"
$PN"11"6;
"VIN2"
$PN"10"6;
"VIN1"
$PN"9"6;
%"Q_RES"
"1","(-2150,-1200)","0","pure_quanta","I15";
;
PART_NUMBER"CS41202FB05"
MATERIAL"CHIP"
WATTAGE"1/16W"
VALUE"120K"
ROOM"HSC1_BOM1"
TOLERANCE"1%"
PACK_TYPE"0402LF"
LOCATION"PR3912"
CDS_LIB"pure_quanta"
$SEC"1"
CDS_SEC"1";
"B"
$PN"2"24;
"A"
$PN"1"9;
%"Q_RES"
"1","(-1550,-1375)","0","pure_quanta","I17";
;
PART_NUMBER"CS00002JB13"
VALUE"0"
WATTAGE"1/16W"
MATERIAL"CHIP"
TOLERANCE"5%"
PACK_TYPE"0402LF"
ROOM"HSC1_BOM1"
LOCATION"PR3917"
CDS_LIB"pure_quanta"
$SEC"1"
CDS_SEC"1";
"B"
$PN"2"25;
"A"
$PN"1"35;
%"UNIVERSAL_POWER"
"1","(-1200,-400)","0","logical_power","I18";
;
HDL_POWER"P12V_PSU"
BOM_COST"MIO_VRD_SB"
CDS_LIB"logical_power"
ROOM"AUX_SW";
"A"6;
%"UNIVERSAL_GND"
"1","(-3675,1125)","0","logical_power","I19";
;
HDL_POWER"AGND_HSC"
CDS_LIB"logical_power";
"A"1;
%"Q_CAP"
"1","(-2875,-2025)","0","pure_quanta","I2";
;
PART_NUMBER"TMP_QCH12206KB14"
VALUE"220PF"
MATERIAL"EMPTY"
PACK_TYPE"0402"
VOLTAGE"50V"
LOCATION"PC2183"
CDS_LIB"pure_quanta"
TOLERANCE"10%"
$SEC"1"
CDS_SEC"1";
"B"
$PN"2"3;
"A"
$PN"1"29;
%"Q_CAP"
"1","(-3675,1425)","0","pure_quanta","I20";
;
PART_NUMBER"CH5104KEB02"
MATERIAL"X6S"
VOLTAGE"25V"
VALUE"1UF"
ROOM"HSC1_BOM1"
PACK_TYPE"C0402"
LOCATION"PC1525"
CDS_LIB"pure_quanta"
TOLERANCE"10%"
$SEC"1"
CDS_SEC"1";
"B"
$PN"2"1;
"A"
$PN"1"17;
%"Q_RES"
"1","(-3675,1900)","1","pure_quanta","I21";
;
PART_NUMBER"CS00002JB13"
WATTAGE"1/16W"
PACK_TYPE"0402LF"
VALUE"0"
ROOM"HSC1_BOM1"
TOLERANCE"5%"
MATERIAL"CHIP"
LOCATION"PR3910"
CDS_LIB"pure_quanta"
$SEC"1"
CDS_SEC"1";
"B"
$PN"2"5;
"A"
$PN"1"17;
%"UNIVERSAL_GND"
"1","(-2900,475)","0","logical_power","I22";
;
HDL_POWER"AGND_HSC"
CDS_LIB"logical_power";
"A"4;
%"Q_CAP"
"1","(-2900,775)","0","pure_quanta","I23";
;
PART_NUMBER"TMP_QCH12206KB14"
MATERIAL"X7R"
PACK_TYPE"0402"
VALUE"220PF"
ROOM"HSC1_BOM1"
VOLTAGE"50V"
LOCATION"PC2182"
TOLERANCE"10%"
CDS_LIB"pure_quanta"
$SEC"1"
CDS_SEC"1";
"B"
$PN"2"4;
"A"
$PN"1"15;
%"UNIVERSAL_GND"
"1","(-2850,1525)","0","logical_power","I25";
;
HDL_POWER"AGND_HSC"
CDS_LIB"logical_power";
"A"2;
%"UNIVERSAL_POWER"
"1","(-3675,2150)","0","logical_power","I28";
;
HDL_POWER"HSC_VDD"
CDS_LIB"logical_power"
BOM_COST"MIO_VRD_SB"
ROOM"AUX_SW";
"A"5;
%"Q_CAP"
"1","(-2225,775)","0","pure_quanta","I29";
;
PART_NUMBER"CH21006KB16"
VOLTAGE"50V"
MATERIAL"EMPTY"
VALUE"1NF"
PACK_TYPE"0402"
LOCATION"PC2347"
TOLERANCE"10%"
CDS_LIB"pure_quanta"
$SEC"1"
CDS_SEC"1";
"B"
$PN"2"4;
"A"
$PN"1"31;
%"UNIVERSAL_GND"
"1","(-3700,-1675)","0","logical_power","I3";
;
HDL_POWER"AGND_HSC"
CDS_LIB"logical_power";
"A"7;
%"Q_RES"
"2","(-1725,775)","0","pure_quanta","I30";
;
PART_NUMBER"CS22002BB07"
ROOM"HSC1_BOM1"
VALUE"2K"
TOLERANCE"0.1%"
WATTAGE"1/16W"
MATERIAL"CHIP"
PACK_TYPE"0402LF"
LOCATION"PR3914"
CDS_LIB"pure_quanta"
$SEC"1"
CDS_SEC"1";
"A"
$PN"1"32;
"B"
$PN"2"4;
%"Q_RES"
"1","(-2150,1600)","0","pure_quanta","I32";
;
PART_NUMBER"CS41202FB05"
MATERIAL"CHIP"
WATTAGE"1/16W"
TOLERANCE"1%"
VALUE"120K"
ROOM"HSC1_BOM1"
PACK_TYPE"0402LF"
$LOCATION"PR1134"
CDS_LIB"pure_quanta"
CDS_LOCATION"PR1134"
$SEC"1"
CDS_SEC"1";
"B"
$PN"2"16;
"A"
$PN"1"2;
%"Q_RES"
"1","(-1575,1425)","0","pure_quanta","I33";
;
PART_NUMBER"CS00002JB13"
VALUE"0"
ROOM"HSC1_BOM1"
MATERIAL"CHIP"
PACK_TYPE"0402LF"
WATTAGE"1/16W"
TOLERANCE"5%"
LOCATION"PR3916"
CDS_LIB"pure_quanta"
$SEC"1"
CDS_SEC"1";
"B"
$PN"2"33;
"A"
$PN"1"18;
%"Q_RES"
"2","(-1200,775)","0","pure_quanta","I34";
;
PART_NUMBER"CS22002BB07"
VALUE"2K"
TOLERANCE"0.1%"
MATERIAL"CHIP"
WATTAGE"1/16W"
ROOM"HSC1_BOM1"
PACK_TYPE"0402LF"
LOCATION"PR3918"
CDS_LIB"pure_quanta"
$SEC"1"
CDS_SEC"1";
"A"
$PN"1"34;
"B"
$PN"2"4;
%"MP5991GLUZ"
"1","(-225,1525)","0","pure_quanta","I35";
;
PART_NUMBER"AL005991A00"
MATERIAL"IC"
VALUE"MP5991GLU-Z"
PART_TYPE"SMLF"
ROOM"HSC1_BOM1"
LOCATION"PU287"
CDS_LIB"pure_quanta"
CDS_LMAN_SYM_OUTLINE"-325,775,325,-775"
NEEDS_NO_SIZE"TRUE"
SEC_TYPE""
SEC"1";
"NC1"
$PN"7"46;
"FLT_TYPE"
$PN"6"20;
"SCREF_OCWREF"
$PN"17"33;
"MODE"
$PN"8"16;
"VOUT10"
$PN"32"14;
"VOUT9"
$PN"31"14;
"VOUT8"
$PN"30"14;
"VOUT7"
$PN"29"14;
"VOUT6"
$PN"28"14;
"VOUT5"
$PN"27"14;
"VIN9"
$PN"33"10;
"VIN8"
$PN"16"10;
"VIN7"
$PN"15"10;
"VIN6"
$PN"14"10;
"D_OC"
$PN"3"19;
"VOUT4"
$PN"26"14;
"VOUT3"
$PN"25"14;
"VOUT2"
$PN"2"14;
"VOUT1"
$PN"1"14;
"VTEMP"
$PN"18"22;
"GOK"
$PN"5"21;
"SS"
$PN"19"23;
"GND"
$PN"20"4;
"VDD33"
$PN"21"17;
"IMON"
$PN"22"34;
"CS"
$PN"23"32;
"OCREF"
$PN"24"31;
"ON"
$PN"4"15;
"VIN5"
$PN"13"10;
"VIN4"
$PN"12"10;
"VIN3"
$PN"11"10;
"VIN2"
$PN"10"10;
"VIN1"
$PN"9"10;
%"UNIVERSAL_POWER"
"1","(-1200,2400)","0","logical_power","I36";
;
HDL_POWER"P12V_PSU"
CDS_LIB"logical_power"
BOM_COST"MIO_VRD_SB"
ROOM"AUX_SW";
"A"10;
%"Q_CAP"
"1","(750,-2000)","0","pure_quanta","I37";
;
PART_NUMBER"CH3683K1B09"
VALUE"0.068UF"
VOLTAGE"16V"
MATERIAL"X7R"
PACK_TYPE"0402"
ROOM"HSC1_BOM1"
LOCATION"PC2185"
CDS_LIB"pure_quanta"
TOLERANCE"10%"
$SEC"1"
CDS_SEC"1";
"B"
$PN"2"11;
"A"
$PN"1"41;
%"UNIVERSAL_GND"
"1","(750,-2225)","0","logical_power","I38";
;
HDL_POWER"AGND_HSC"
CDS_LIB"logical_power";
"A"11;
%"Q_RES"
"1","(1250,-1275)","0","pure_quanta","I39";
;
PART_NUMBER"CS00002JB13"
TOLERANCE"5%"
PACK_TYPE"0402LF"
VALUE"0"
WATTAGE"1/16W"
MATERIAL"CHIP"
ROOM"HSC1_BOM1"
LOCATION"PR3921"
CDS_LIB"pure_quanta"
$SEC"1"
CDS_SEC"1";
"B"
$PN"2"37;
"A"
$PN"1"45;
%"Q_CAP"
"1","(-3700,-1375)","0","pure_quanta","I4";
;
PART_NUMBER"CH5104KEB02"
VALUE"1UF"
PACK_TYPE"C0402"
MATERIAL"X6S"
VOLTAGE"25V"
ROOM"HSC1_BOM1"
LOCATION"PC2181"
CDS_LIB"pure_quanta"
TOLERANCE"10%"
$SEC"1"
CDS_SEC"1";
"B"
$PN"2"7;
"A"
$PN"1"30;
%"Q_RES"
"1","(1250,-1450)","0","pure_quanta","I40";
;
PART_NUMBER"CS00002JB13"
VALUE"0"
TOLERANCE"5%"
MATERIAL"CHIP"
WATTAGE"1/16W"
PACK_TYPE"0402LF"
ROOM"HSC1_BOM1"
LOCATION"PR3922"
CDS_LIB"pure_quanta"
$SEC"1"
CDS_SEC"1";
"B"
$PN"2"38;
"A"
$PN"1"44;
%"UNIVERSAL_POWER"
"1","(875,-400)","0","logical_power","I41";
;
HDL_POWER"P12V_AUX"
BOM_COST"MIO_VRD_SB"
CDS_LIB"logical_power"
ROOM"AUX_SW";
"A"12;
%"Q_CAP"
"1","(750,800)","0","pure_quanta","I47";
;
PART_NUMBER"CH3683K1B09"
VALUE"0.068UF"
MATERIAL"X7R"
PACK_TYPE"0402"
VOLTAGE"16V"
ROOM"HSC1_BOM1"
LOCATION"PC2184"
CDS_LIB"pure_quanta"
TOLERANCE"10%"
$SEC"1"
CDS_SEC"1";
"B"
$PN"2"13;
"A"
$PN"1"23;
%"UNIVERSAL_GND"
"1","(750,575)","0","logical_power","I48";
;
HDL_POWER"AGND_HSC"
CDS_LIB"logical_power";
"A"13;
%"Q_RES"
"1","(1250,1525)","0","pure_quanta","I49";
;
PART_NUMBER"CS00002JB13"
VALUE"0"
TOLERANCE"5%"
MATERIAL"CHIP"
ROOM"HSC1_BOM1"
PACK_TYPE"0402LF"
WATTAGE"1/16W"
LOCATION"PR3919"
CDS_LIB"pure_quanta"
$SEC"1"
CDS_SEC"1";
"B"
$PN"2"40;
"A"
$PN"1"19;
%"Q_RES"
"1","(-3700,-900)","1","pure_quanta","I5";
;
PART_NUMBER"CS00002JB13"
TOLERANCE"5%"
MATERIAL"CHIP"
WATTAGE"1/16W"
PACK_TYPE"0402LF"
VALUE"0"
ROOM"HSC1_BOM1"
LOCATION"PR3911"
CDS_LIB"pure_quanta"
$SEC"1"
CDS_SEC"1";
"B"
$PN"2"8;
"A"
$PN"1"30;
%"Q_RES"
"1","(1250,1350)","0","pure_quanta","I50";
;
PART_NUMBER"CS00002JB13"
VALUE"0"
ROOM"HSC1_BOM1"
PACK_TYPE"0402LF"
MATERIAL"CHIP"
TOLERANCE"5%"
WATTAGE"1/16W"
LOCATION"PR3920"
CDS_LIB"pure_quanta"
$SEC"1"
CDS_SEC"1";
"B"
$PN"2"39;
"A"
$PN"1"20;
%"UNIVERSAL_POWER"
"1","(875,2400)","0","logical_power","I51";
;
HDL_POWER"P12V_AUX"
CDS_LIB"logical_power"
BOM_COST"MIO_VRD_SB"
ROOM"AUX_SW";
"A"14;
%"UNIVERSAL_POWER"
"1","(-3700,-650)","0","logical_power","I6";
;
HDL_POWER"HSC_VDD"
CDS_LIB"logical_power"
BOM_COST"MIO_VRD_SB"
ROOM"AUX_SW";
"A"8;
%"UNIVERSAL_GND"
"1","(-2950,-1300)","0","logical_power","I8";
;
HDL_POWER"AGND_HSC"
CDS_LIB"logical_power";
"A"9;
END.
